# SCM (Grand Teton) — schematic netlist excerpt (pin names and nets, part order shuffled) for the footprints in the layout excerpt that follows; sources: Cadence DE-HDL packaged netlist, KiCad conversion of 12092022_DA0F0TMDCD0_F0T_Management_Board_D_brd_V3_OCP.brd

R598  Q_RES  750 1% CHIP  pkg 0402LF  page 47 : A = LED_POSTCODE_6 ; B = LED_POSTCODE_6_R
C174  Q_CAP  0.1UF 25V 10% EMPTY  pkg 0402  page 10 : A = P3V_BAT_R ; B = GND

(kicad_pcb
	(version 20260206)
	(generator "pcbnew")
	(generator_version "10.0")
	(general
		(thickness 1.6)
		(legacy_teardrops no)
	)
	(paper "A4")
	(title_block
		(title "12092022_DA0F0TMDCD0_F0T_Management_Board_D_brd_V3_OCP.brd")
		(comment 1 "Grand Teton / footprints 149-150 of 1440")
	)
	(layers
		(0 "F.Cu" signal "TOP")
		(4 "In1.Cu" signal "GND")
		(6 "In2.Cu" signal "IN1")
		(8 "In3.Cu" signal "GND1")
		(10 "In4.Cu" signal "IN2")
		(12 "In5.Cu" signal "VCC")
		(14 "In6.Cu" signal "VCC1")
		(16 "In7.Cu" signal "IN3")
		(18 "In8.Cu" signal "GND2")
		(20 "In9.Cu" signal "IN4")
		(22 "In10.Cu" signal "GND3")
		(2 "B.Cu" signal "BOTTOM")
		(9 "F.Adhes" user "F.Adhesive")
		(11 "B.Adhes" user "B.Adhesive")
		(13 "F.Paste" user "Package Geometry/Pastemask Top")
		(15 "B.Paste" user "Package Geometry/Pastemask Bottom")
		(5 "F.SilkS" user "Ref Des/Silkscreen Top")
		(7 "B.SilkS" user "Ref Des/Silkscreen Bottom")
		(1 "F.Mask" user "Board Geometry/Soldermask Top")
		(3 "B.Mask" user "Board Geometry/Soldermask Bottom")
		(17 "Dwgs.User" user "User.Drawings")
		(19 "Cmts.User" user "User.Comments")
		(21 "Eco1.User" user "User.Eco1")
		(23 "Eco2.User" user "User.Eco2")
		(25 "Edge.Cuts" user "Board Geometry/Outline")
		(27 "Margin" user)
		(31 "F.CrtYd" user "Package Geometry/Place Bound Top")
		(29 "B.CrtYd" user "Package Geometry/Place Bound Bottom")
		(35 "F.Fab" user "Ref Des/Assembly Top")
		(33 "B.Fab" user "Ref Des/Assembly Bottom")
	)
	(footprint ""
		(layer "F.Cu")
		(at 32.8422 -108.585 -90)
		(property "Reference" "C174"
			(at 0 0 270)
			(layer "F.SilkS")
			(hide yes)
			(effects
				(font
					(size 1.27 1.27)
				)
			)
		)
		(property "Value" ""
			(at 0 0 270)
			(layer "F.Fab")
			(effects
				(font
					(size 1.27 1.27)
				)
			)
		)
		(duplicate_pad_numbers_are_jumpers no)
		(fp_line
			(start -0.7874 0.4064)
			(end -0.7874 -0.4064)
			(stroke
				(width 0.1524)
				(type default)
			)
			(layer "F.SilkS")
		)
		(fp_line
			(start 0.7874 0.4064)
			(end -0.7874 0.4064)
			(stroke
				(width 0.1524)
				(type default)
			)
			(layer "F.SilkS")
		)
		(fp_line
			(start -0.7874 -0.4064)
			(end 0.7874 -0.4064)
			(stroke
				(width 0.1524)
				(type default)
			)
			(layer "F.SilkS")
		)
		(fp_line
			(start 0.7874 -0.4064)
			(end 0.7874 0.4064)
			(stroke
				(width 0.1524)
				(type default)
			)
			(layer "F.SilkS")
		)
		(fp_line
			(start -0.67945 0.3048)
			(end -0.67945 -0.305054)
			(stroke
				(width 0.1)
				(type default)
			)
			(layer "F.Fab")
		)
		(fp_line
			(start -0.12065 0.3048)
			(end -0.67945 0.3048)
			(stroke
				(width 0.1)
				(type default)
			)
			(layer "F.Fab")
		)
		(fp_line
			(start 0.120396 0.3048)
			(end 0.120396 0.2794)
			(stroke
				(width 0.1)
				(type default)
			)
			(layer "F.Fab")
		)
		(fp_line
			(start 0.67945 0.3048)
			(end 0.120396 0.3048)
			(stroke
				(width 0.1)
				(type default)
			)
			(layer "F.Fab")
		)
		(fp_line
			(start -0.12065 0.2794)
			(end -0.12065 0.3048)
			(stroke
				(width 0.1)
				(type default)
			)
			(layer "F.Fab")
		)
		(fp_line
			(start 0.120396 0.2794)
			(end -0.12065 0.2794)
			(stroke
				(width 0.1)
				(type default)
			)
			(layer "F.Fab")
		)
		(fp_line
			(start -0.12065 -0.2794)
			(end 0.12065 -0.2794)
			(stroke
				(width 0.1)
				(type default)
			)
			(layer "F.Fab")
		)
		(fp_line
			(start 0.12065 -0.2794)
			(end 0.12065 -0.3048)
			(stroke
				(width 0.1)
				(type default)
			)
			(layer "F.Fab")
		)
		(fp_line
			(start 0.12065 -0.3048)
			(end 0.67945 -0.3048)
			(stroke
				(width 0.1)
				(type default)
			)
			(layer "F.Fab")
		)
		(fp_line
			(start 0.67945 -0.3048)
			(end 0.67945 0.3048)
			(stroke
				(width 0.1)
				(type default)
			)
			(layer "F.Fab")
		)
		(fp_line
			(start -0.67945 -0.305054)
			(end -0.12065 -0.305054)
			(stroke
				(width 0.1)
				(type default)
			)
			(layer "F.Fab")
		)
		(fp_line
			(start -0.12065 -0.305054)
			(end -0.12065 -0.2794)
			(stroke
				(width 0.1)
				(type default)
			)
			(layer "F.Fab")
		)
		(pad "1" smd circle
			(at -0.40005 0 270)
			(size 0 0)
			(layers "F.Cu" "F.Mask" "F.Paste")
			(net "P3V_BAT_R")
		)
		(pad "2" smd circle
			(at 0.40005 0 270)
			(size 0 0)
			(layers "F.Cu" "F.Mask" "F.Paste")
			(net "GND")
		)
	)
	(footprint ""
		(layer "F.Cu")
		(at 72.46493 -33.011618 90)
		(property "Reference" "R598"
			(at 0 0 90)
			(layer "F.SilkS")
			(hide yes)
			(effects
				(font
					(size 1.27 1.27)
				)
			)
		)
		(property "Value" ""
			(at 0 0 90)
			(layer "F.Fab")
			(effects
				(font
					(size 1.27 1.27)
				)
			)
		)
		(duplicate_pad_numbers_are_jumpers no)
		(fp_line
			(start 0.7874 -0.4064)
			(end 0.7874 0.4064)
			(stroke
				(width 0.1524)
				(type default)
			)
			(layer "F.SilkS")
		)
		(fp_line
			(start -0.7874 -0.4064)
			(end 0.7874 -0.4064)
			(stroke
				(width 0.1524)
				(type default)
			)
			(layer "F.SilkS")
		)
		(fp_line
			(start 0.7874 0.4064)
			(end -0.7874 0.4064)
			(stroke
				(width 0.1524)
				(type default)
			)
			(layer "F.SilkS")
		)
		(fp_line
			(start -0.7874 0.4064)
			(end -0.7874 -0.4064)
			(stroke
				(width 0.1524)
				(type default)
			)
			(layer "F.SilkS")
		)
		(fp_line
			(start -0.12065 -0.305054)
			(end -0.12065 -0.2794)
			(stroke
				(width 0.1)
				(type default)
			)
			(layer "F.Fab")
		)
		(fp_line
			(start -0.67945 -0.305054)
			(end -0.12065 -0.305054)
			(stroke
				(width 0.1)
				(type default)
			)
			(layer "F.Fab")
		)
		(fp_line
			(start 0.67945 -0.3048)
			(end 0.67945 0.3048)
			(stroke
				(width 0.1)
				(type default)
			)
			(layer "F.Fab")
		)
		(fp_line
			(start 0.12065 -0.3048)
			(end 0.67945 -0.3048)
			(stroke
				(width 0.1)
				(type default)
			)
			(layer "F.Fab")
		)
		(fp_line
			(start 0.12065 -0.2794)
			(end 0.12065 -0.3048)
			(stroke
				(width 0.1)
				(type default)
			)
			(layer "F.Fab")
		)
		(fp_line
			(start -0.12065 -0.2794)
			(end 0.12065 -0.2794)
			(stroke
				(width 0.1)
				(type default)
			)
			(layer "F.Fab")
		)
		(fp_line
			(start 0.120396 0.2794)
			(end -0.12065 0.2794)
			(stroke
				(width 0.1)
				(type default)
			)
			(layer "F.Fab")
		)
		(fp_line
			(start -0.12065 0.2794)
			(end -0.12065 0.3048)
			(stroke
				(width 0.1)
				(type default)
			)
			(layer "F.Fab")
		)
		(fp_line
			(start 0.67945 0.3048)
			(end 0.120396 0.3048)
			(stroke
				(width 0.1)
				(type default)
			)
			(layer "F.Fab")
		)
		(fp_line
			(start 0.120396 0.3048)
			(end 0.120396 0.2794)
			(stroke
				(width 0.1)
				(type default)
			)
			(layer "F.Fab")
		)
		(fp_line
			(start -0.12065 0.3048)
			(end -0.67945 0.3048)
			(stroke
				(width 0.1)
				(type default)
			)
			(layer "F.Fab")
		)
		(fp_line
			(start -0.67945 0.3048)
			(end -0.67945 -0.305054)
			(stroke
				(width 0.1)
				(type default)
			)
			(layer "F.Fab")
		)
		(pad "1" smd circle
			(at -0.40005 0 90)
			(size 0 0)
			(layers "F.Cu" "F.Mask" "F.Paste")
			(net "LED_POSTCODE_6")
		)
		(pad "2" smd circle
			(at 0.40005 0 90)
			(size 0 0)
			(layers "F.Cu" "F.Mask" "F.Paste")
			(net "LED_POSTCODE_6_R")
		)
	)
)
